# S9S_MB_2U (Grand Teton) — schematic parts with pin connectivity, parts 1609–1609 of 6093; source: Cadence DE-HDL packaged netlist (pstxprt.dat, pstxnet.dat, pstchip.dat)

J16  SCONN288_ADR50017P087CC  SCONN288_ADR50017-P087CC IO  pkg DDR288S_1-1VXB  page 97
  1  VIN_BULK0  POWER  = P12V_S3_AUX_CPU0_NVDIMM
  2  RFU0  TRI  = TP_CHH_CPU0_DIMM2_FRU_0
  3  VIN_MGMT  POWER  = P3V3_AUX
  4  HSCL  IN  = I3C_SPD_DDREFGH_CPU0_LVC1_SCL_7
  5  HSDA  BI  = I3C_SPD_DDREFGH_CPU0_LVC1_SDA
  6  VSS0  POWER  = GND
  7  DQ0_A  BI  = M_H_CPU0_SA_DQ<0>
  8  VSS1  POWER  = GND
  9  DQ1_A  BI  = M_H_CPU0_SA_DQ<1>
  10  VSS2  POWER  = GND
  11  DQS0_A_T  BI  = M_H_CPU0_SA_DQS_DP<0>
  12  DQS0_A_C  BI  = M_H_CPU0_SA_DQS_DN<0>
  13  VSS3  POWER  = GND
  14  DQ4_A  BI  = M_H_CPU0_SA_DQ<4>
  15  VSS4  POWER  = GND
  16  DQ5_A  BI  = M_H_CPU0_SA_DQ<5>
  17  VSS5  POWER  = GND
  18  DQ8_A  BI  = M_H_CPU0_SA_DQ<8>
  19  VSS6  POWER  = GND
  20  DQ9_A  BI  = M_H_CPU0_SA_DQ<9>
  21  VSS7  POWER  = GND
  22  DQS1_A_T  BI  = M_H_CPU0_SA_DQS_DP<1>
  23  DQS1_A_C  BI  = M_H_CPU0_SA_DQS_DN<1>
  24  VSS8  POWER  = GND
  25  DQ12_A  BI  = M_H_CPU0_SA_DQ<12>
  26  VSS9  POWER  = GND
  27  DQ13_A  BI  = M_H_CPU0_SA_DQ<13>
  28  VSS10  POWER  = GND
  29  DQ16_A  BI  = M_H_CPU0_SA_DQ<16>
  30  VSS11  POWER  = GND
  31  DQ17_A  BI  = M_H_CPU0_SA_DQ<17>
  32  VSS12  POWER  = GND
  33  DQS2_A_T  BI  = M_H_CPU0_SA_DQS_DP<2>
  34  DQS2_A_C  BI  = M_H_CPU0_SA_DQS_DN<2>
  35  VSS13  POWER  = GND
  36  DQ20_A  BI  = M_H_CPU0_SA_DQ<20>
  37  VSS14  POWER  = GND
  38  DQ21_A  BI  = M_H_CPU0_SA_DQ<21>
  39  VSS15  POWER  = GND
  40  DQ24_A  BI  = M_H_CPU0_SA_DQ<24>
  41  VSS16  POWER  = GND
  42  DQ25_A  BI  = M_H_CPU0_SA_DQ<25>
  43  VSS17  POWER  = GND
  44  DQS3_A_T  BI  = M_H_CPU0_SA_DQS_DP<3>
  45  DQS3_A_C  BI  = M_H_CPU0_SA_DQS_DN<3>
  46  VSS18  POWER  = GND
  47  DQ28_A  BI  = M_H_CPU0_SA_DQ<28>
  48  VSS19  POWER  = GND
  49  DQ29_A  BI  = M_H_CPU0_SA_DQ<29>
  50  VSS20  POWER  = GND
  51  CB0_A  BI  = M_H_CPU0_SA_CB<0>
  52  VSS21  POWER  = GND
  53  CB1_A  BI  = M_H_CPU0_SA_CB<1>
  54  VSS22  POWER  = GND
  55  DQS4_A_T  BI  = M_H_CPU0_SA_DQS_DP<4>
  56  DQS4_A_C  BI  = M_H_CPU0_SA_DQS_DN<4>
  57  VSS23  POWER  = GND
  58  CB4_A  BI  = M_H_CPU0_SA_CB<4>
  59  VSS24  POWER  = GND
  60  CB5_A  BI  = M_H_CPU0_SA_CB<5>
  61  VSS25  POWER  = GND
  62  ALERT_N  OUT  = M_H_CPU0_ALERT_N
  63  VSS26  POWER  = GND
  64  CS0_A_N  IN  = M_H_CPU0_SA_CS_N<2>
  65  VSS27  POWER  = GND
  66  CA0_A  IN  = M_H_CPU0_SA_CA<0>
  67  VSS28  POWER  = GND
  68  CA2_A  IN  = M_H_CPU0_SA_CA<2>
  69  VSS29  POWER  = GND
  70  CA4_A  IN  = M_H_CPU0_SA_CA<4>
  71  VSS30  POWER  = GND
  72  CA6_A  IN  = M_H_CPU0_SA_CA<6>
  73  VSS31  POWER  = GND
  74  PAR_A  IN  = M_H_CPU0_SA_PAR
  75  VSS32  POWER  = GND
  76  CA0_B  IN  = M_H_CPU0_SB_CA<0>
  77  VSS33  POWER  = GND
  78  CA2_B  IN  = M_H_CPU0_SB_CA<2>
  79  VSS34  POWER  = GND
  80  CA4_B  IN  = M_H_CPU0_SB_CA<4>
  81  VSS35  POWER  = GND
  82  CA6_B  IN  = M_H_CPU0_SB_CA<6>
  83  VSS36  POWER  = GND
  84  CS0_B_N  IN  = M_H_CPU0_SB_CS_N<2>
  85  VSS37  POWER  = GND
  86  \lbd||rsp_a_n\  OUT  = M_H_CPU0_SA_RSP<1>
  87  \lbs||rsp_b_n\  OUT  = M_H_CPU0_SB_RSP<1>
  88  VSS38  POWER  = GND
  89  CB4_B  BI  = M_H_CPU0_SB_CB<4>
  90  VSS39  POWER  = GND
  91  CB5_B  BI  = M_H_CPU0_SB_CB<5>
  92  VSS40  POWER  = GND
  93  \dqs9_b_t||tdqs9_b_t||dbi4_b_n\  BI  = M_H_CPU0_SB_DQS_DP<9>
  94  \dqs9_b_c||tdqs9_b_c\  BI  = M_H_CPU0_SB_DQS_DN<9>
  95  VSS41  POWER  = GND
  96  CB0_B  BI  = M_H_CPU0_SB_CB<0>
  97  VSS42  POWER  = GND
  98  CB1_B  BI  = M_H_CPU0_SB_CB<1>
  99  VSS43  POWER  = GND
  100  DQ0_B  BI  = M_H_CPU0_SB_DQ<0>
  101  VSS44  POWER  = GND
  102  DQ1_B  BI  = M_H_CPU0_SB_DQ<1>
  103  VSS45  POWER  = GND
  104  DQS0_B_T  BI  = M_H_CPU0_SB_DQS_DP<0>
  105  DQS0_B_C  BI  = M_H_CPU0_SB_DQS_DN<0>
  106  VSS46  POWER  = GND
  107  DQ4_B  BI  = M_H_CPU0_SB_DQ<4>
  108  VSS47  POWER  = GND
  109  DQ5_B  BI  = M_H_CPU0_SB_DQ<5>
  110  VSS48  POWER  = GND
  111  DQ8_B  BI  = M_H_CPU0_SB_DQ<8>
  112  VSS49  POWER  = GND
  113  DQ9_B  BI  = M_H_CPU0_SB_DQ<9>
  114  VSS50  POWER  = GND
  115  DQS1_B_T  BI  = M_H_CPU0_SB_DQS_DP<1>
  116  DQS1_B_C  BI  = M_H_CPU0_SB_DQS_DN<1>
  117  VSS51  POWER  = GND
  118  DQ12_B  BI  = M_H_CPU0_SB_DQ<12>
  119  VSS52  POWER  = GND
  120  DQ13_B  BI  = M_H_CPU0_SB_DQ<13>
  121  VSS53  POWER  = GND
  122  DQ16_B  BI  = M_H_CPU0_SB_DQ<16>
  123  VSS54  POWER  = GND
  124  DQ17_B  BI  = M_H_CPU0_SB_DQ<17>
  125  VSS55  POWER  = GND
  126  DQS2_B_T  BI  = M_H_CPU0_SB_DQS_DP<2>
  127  DQS2_B_C  BI  = M_H_CPU0_SB_DQS_DN<2>
  128  VSS56  POWER  = GND
  129  DQ20_B  BI  = M_H_CPU0_SB_DQ<20>
  130  VSS57  POWER  = GND
  131  DQ21_B  BI  = M_H_CPU0_SB_DQ<21>
  132  VSS58  POWER  = GND
  133  DQ24_B  BI  = M_H_CPU0_SB_DQ<24>
  134  VSS59  POWER  = GND
  135  DQ25_B  BI  = M_H_CPU0_SB_DQ<25>
  136  VSS60  POWER  = GND
  137  DQS3_B_T  BI  = M_H_CPU0_SB_DQS_DP<3>
  138  DQS3_B_C  BI  = M_H_CPU0_SB_DQS_DN<3>
  139  VSS61  POWER  = GND
  140  DQ28_B  BI  = M_H_CPU0_SB_DQ<28>
  141  VSS62  POWER  = GND
  142  DQ29_B  BI  = M_H_CPU0_SB_DQ<29>
  143  VSS63  POWER  = GND
  144  RFU1  TRI  = TP_CHH_CPU0_DIMM2_FRU_1
  145  VIN_BULK1  POWER  = P12V_S3_AUX_CPU0_NVDIMM
  146  VIN_BULK2  POWER  = P12V_S3_AUX_CPU0_NVDIMM
  147  \pwr_good||fail_n\  BI  = PWRGD_CHH_CPU0_DIMM2
  148  HSA  IN  = PD_CHH_CPU0_DIMM2_SAA
  149  RFU2  TRI  = TP_CHH_CPU0_DIMM2_FRU_2
  150  RFU3  TRI  = TP_CHH_CPU0_DIMM2_FRU_3
  151  VSS64  POWER  = GND
  152  DQ2_A  BI  = M_H_CPU0_SA_DQ<2>
  153  VSS65  POWER  = GND
  154  DQ3_A  BI  = M_H_CPU0_SA_DQ<3>
  155  VSS66  POWER  = GND
  156  \dqs5_a_c||tdqs5_a_c||dqs5_a_t||tdqs5_a_t\  BI  = M_H_CPU0_SA_DQS_DN<5>
  157  \dqs5_a_t||tdqs5_a_t\  BI  = M_H_CPU0_SA_DQS_DP<5>
  158  VSS67  POWER  = GND
  159  DQ6_A  BI  = M_H_CPU0_SA_DQ<6>
  160  VSS68  POWER  = GND
  161  DQ7_A  BI  = M_H_CPU0_SA_DQ<7>
  162  VSS69  POWER  = GND
  163  DQ10_A  BI  = M_H_CPU0_SA_DQ<10>
  164  VSS70  POWER  = GND
  165  DQ11_A  BI  = M_H_CPU0_SA_DQ<11>
  166  VSS71  POWER  = GND
  167  \dqs6_a_c||tdqs6_a_c||dqs6_a_t||tdqs6_a_t\  BI  = M_H_CPU0_SA_DQS_DN<6>
  168  \dqs6_a_t||tdqs6_a_t\  BI  = M_H_CPU0_SA_DQS_DP<6>
  169  VSS72  POWER  = GND
  170  DQ14_A  BI  = M_H_CPU0_SA_DQ<14>
  171  VSS73  POWER  = GND
  172  DQ15_A  BI  = M_H_CPU0_SA_DQ<15>
  173  VSS74  POWER  = GND
  174  DQ18_A  BI  = M_H_CPU0_SA_DQ<18>
  175  VSS75  POWER  = GND
  176  DQ19_A  BI  = M_H_CPU0_SA_DQ<19>
  177  VSS76  POWER  = GND
  178  \dqs7_a_c||tdqs7_a_c\  BI  = M_H_CPU0_SA_DQS_DN<7>
  179  \dqs7_a_t||tdqs7_a_t\  BI  = M_H_CPU0_SA_DQS_DP<7>
  180  VSS77  POWER  = GND
  181  DQ22_A  BI  = M_H_CPU0_SA_DQ<22>
  182  VSS78  POWER  = GND
  183  DQ23_A  BI  = M_H_CPU0_SA_DQ<23>
  184  VSS79  POWER  = GND
  185  DQ26_A  BI  = M_H_CPU0_SA_DQ<26>
  186  VSS80  POWER  = GND
  187  DQ27_A  BI  = M_H_CPU0_SA_DQ<27>
  188  VSS81  POWER  = GND
  189  \dqs8_a_c||tdqs8_a_c\  BI  = M_H_CPU0_SA_DQS_DN<8>
  190  \dqs8_a_t||tdqs8_a_t\  BI  = M_H_CPU0_SA_DQS_DP<8>
  191  VSS82  POWER  = GND
  192  DQ30_A  BI  = M_H_CPU0_SA_DQ<30>
  193  VSS83  POWER  = GND
  194  DQ31_A  BI  = M_H_CPU0_SA_DQ<31>
  195  VSS84  POWER  = GND
  196  CB2_A  BI  = M_H_CPU0_SA_CB<2>
  197  VSS85  POWER  = GND
  198  CB3_A  BI  = M_H_CPU0_SA_CB<3>
  199  VSS86  POWER  = GND
  200  \dqs9_a_c||tdqs9_a_c\  BI  = M_H_CPU0_SA_DQS_DN<9>
  201  \dqs9_a_t||tdqs9_a_t\  BI  = M_H_CPU0_SA_DQS_DP<9>
  202  VSS87  POWER  = GND
  203  CB6_A  BI  = M_H_CPU0_SA_CB<6>
  204  VSS88  POWER  = GND
  205  CB7_A  BI  = M_H_CPU0_SA_CB<7>
  206  VSS89  POWER  = GND
  207  RESET_N  IN  = RST_M_GH_CPU0_FPGA_N
  208  VSS90  POWER  = GND
  209  CS1_A_N  IN  = M_H_CPU0_SA_CS_N<3>
  210  VSS91  POWER  = GND
  211  CA1_A  IN  = M_H_CPU0_SA_CA<1>
  212  VSS92  POWER  = GND
  213  CA3_A  IN  = M_H_CPU0_SA_CA<3>
  214  VSS93  POWER  = GND
  215  CA5_A  IN  = M_H_CPU0_SA_CA<5>
  216  VSS94  POWER  = GND
  217  CK_T  IN  = M_H_CPU0_CLK_DP<1>
  218  CK_C  IN  = M_H_CPU0_CLK_DN<1>
  219  VSS95  POWER  = GND
  220  RFU4  TRI  = TP_CHH_CPU0_DIMM2_FRU_4
  221  CA1_B  IN  = M_H_CPU0_SB_CA<1>
  222  VSS96  POWER  = GND
  223  CA3_B  IN  = M_H_CPU0_SB_CA<3>
  224  VSS97  POWER  = GND
  225  CA5_B  IN  = M_H_CPU0_SB_CA<5>
  226  VSS98  POWER  = GND
  227  PAR_B  IN  = M_H_CPU0_SB_PAR
  228  VSS99  POWER  = GND
  229  CS1_B_N  IN  = M_H_CPU0_SB_CS_N<3>
  230  VSS100  POWER  = GND
  231  RFU5  TRI  = TP_CHH_CPU0_DIMM2_FRU_5
  232  RFU6  TRI  = TP_CHH_CPU0_DIMM2_FRU_6
  233  VSS101  POWER  = GND
  234  CB6_B  BI  = M_H_CPU0_SB_CB<6>
  235  VSS102  POWER  = GND
  236  CB7_B  BI  = M_H_CPU0_SB_CB<7>
  237  VSS103  POWER  = GND
  238  DQS4_B_C  BI  = M_H_CPU0_SB_DQS_DN<4>
  239  DQS4_B_T  BI  = M_H_CPU0_SB_DQS_DP<4>
  240  VSS104  POWER  = GND
  241  CB2_B  BI  = M_H_CPU0_SB_CB<2>
  242  VSS105  POWER  = GND
  243  CB3_B  BI  = M_H_CPU0_SB_CB<3>
  244  VSS106  POWER  = GND
  245  DQ2_B  BI  = M_H_CPU0_SB_DQ<2>
  246  VSS107  POWER  = GND
  247  DQ3_B  BI  = M_H_CPU0_SB_DQ<3>
  248  VSS108  POWER  = GND
  249  \dqs5_b_c||tdqs5_b_c\  BI  = M_H_CPU0_SB_DQS_DN<5>
  250  \dqs5_b_t||tdqs5_b_t\  BI  = M_H_CPU0_SB_DQS_DP<5>
  251  VSS109  POWER  = GND
  252  DQ6_B  BI  = M_H_CPU0_SB_DQ<6>
  253  VSS110  POWER  = GND
  254  DQ7_B  BI  = M_H_CPU0_SB_DQ<7>
  255  VSS111  POWER  = GND
  256  DQ10_B  BI  = M_H_CPU0_SB_DQ<10>
  257  VSS112  POWER  = GND
  258  DQ11_B  BI  = M_H_CPU0_SB_DQ<11>
  259  VSS113  POWER  = GND
  260  \dqs6_b_c||tdqs6_b_c\  BI  = M_H_CPU0_SB_DQS_DN<6>
  261  \dqs6_b_t||tdqs6_b_t\  BI  = M_H_CPU0_SB_DQS_DP<6>
  262  VSS114  POWER  = GND
  263  DQ14_B  BI  = M_H_CPU0_SB_DQ<14>
  264  VSS115  POWER  = GND
  265  DQ15_B  BI  = M_H_CPU0_SB_DQ<15>
  266  VSS116  POWER  = GND
  267  DQ18_B  BI  = M_H_CPU0_SB_DQ<18>
  268  VSS117  POWER  = GND
  269  DQ19_B  BI  = M_H_CPU0_SB_DQ<19>
  270  VSS118  POWER  = GND
  271  \dqs7_b_c||tdqs7_b_c\  BI  = M_H_CPU0_SB_DQS_DN<7>
  272  \dqs7_b_t||tdqs7_b_t\  BI  = M_H_CPU0_SB_DQS_DP<7>
  273  VSS119  POWER  = GND
  274  DQ22_B  BI  = M_H_CPU0_SB_DQ<22>
  275  VSS120  POWER  = GND
  276  DQ23_B  BI  = M_H_CPU0_SB_DQ<23>
  277  VSS121  POWER  = GND
  278  DQ26_B  BI  = M_H_CPU0_SB_DQ<26>
  279  VSS122  POWER  = GND
  280  DQ27_B  BI  = M_H_CPU0_SB_DQ<27>
  281  VSS123  POWER  = GND
  282  \dqs8_b_c||tdqs8_b_c\  BI  = M_H_CPU0_SB_DQS_DN<8>
  283  \dqs8_b_t||tdqs8_b_t\  BI  = M_H_CPU0_SB_DQS_DP<8>
  284  VSS124  POWER  = GND
  285  DQ30_B  BI  = M_H_CPU0_SB_DQ<30>
  286  VSS125  POWER  = GND
  287  DQ31_B  BI  = M_H_CPU0_SB_DQ<31>
  288  VSS126  POWER  = GND
  G1  G1  POWER  = GND
  G2  G2  POWER  = GND
  G3  G3  POWER  = GND
